(kicad_pcb
	(version 20260206)
	(generator "pcbnew")
	(generator_version "10.0")
	(general
		(thickness 1.6)
		(legacy_teardrops no)
	)
	(paper "A4")
	(title_block
		(title "panther-plus-userver — 13130-1b_20150205.brd")
		(comment 1 "Honey Badger (Wiwynn) / footprint 408 of 1509 (U14), pads 1-121 of 145")
	)
	(layers
		(0 "F.Cu" signal "TOP")
		(4 "In1.Cu" signal "L2")
		(6 "In2.Cu" signal "L3")
		(8 "In3.Cu" signal "L4")
		(10 "In4.Cu" signal "L5")
		(12 "In5.Cu" signal "L6")
		(14 "In6.Cu" signal "L7")
		(16 "In7.Cu" signal "L8")
		(18 "In8.Cu" signal "L9")
		(20 "In9.Cu" signal "L10")
		(22 "In10.Cu" signal "L11")
		(2 "B.Cu" signal "BOTTOM")
		(9 "F.Adhes" user "F.Adhesive")
		(11 "B.Adhes" user "B.Adhesive")
		(13 "F.Paste" user "Package Geometry/Pastemask Top")
		(15 "B.Paste" user "Package Geometry/Pastemask Bottom")
		(5 "F.SilkS" user "Ref Des/Silkscreen Top")
		(7 "B.SilkS" user "Ref Des/Silkscreen Bottom")
		(1 "F.Mask" user "Board Geometry/Soldermask Top")
		(3 "B.Mask" user "Board Geometry/Soldermask Bottom")
		(17 "Dwgs.User" user "User.Drawings")
		(19 "Cmts.User" user "User.Comments")
		(21 "Eco1.User" user "User.Eco1")
		(23 "Eco2.User" user "User.Eco2")
		(25 "Edge.Cuts" user "Board Geometry/Outline")
		(27 "Margin" user)
		(31 "F.CrtYd" user "Package Geometry/Place Bound Top")
		(29 "B.CrtYd" user "Package Geometry/Place Bound Bottom")
		(35 "F.Fab" user "Ref Des/Assembly Top")
		(33 "B.Fab" user "Ref Des/Assembly Bottom")
	)
	(footprint ""
		(layer "F.Cu")
		(at 142.748 -34.544)
		(property "Reference" "U14"
			(at 0 0 0)
			(layer "F.SilkS")
			(hide yes)
			(effects
				(font
					(size 1.27 1.27)
				)
			)
		)
		(property "Value" "EP4CE6E22C8N-GP"
			(at 13.9065 9.4361 0)
			(unlocked yes)
			(layer "F.Fab")
			(hide yes)
			(effects
				(font
					(size 1.016 1.016)
					(thickness 0.1524)
				)
			)
		)
		(property "Device Type" "TQFP144-G6H65"
			(at 13.9065 7.9121 0)
			(unlocked yes)
			(layer "F.Fab")
			(hide yes)
			(effects
				(font
					(size 1.016 1.016)
					(thickness 0.1524)
				)
			)
		)
		(duplicate_pad_numbers_are_jumpers no)
		(pad "1" smd rect
			(at 8.7503 -10.6172)
			(size 0.3048 1.27)
			(layers "F.Cu" "F.Mask" "F.Paste")
			(net "BMC_I2C_DATA")
		)
		(pad "2" smd rect
			(at 8.24992 -10.6172)
			(size 0.3048 1.27)
			(layers "F.Cu" "F.Mask" "F.Paste")
			(net "BMC_I2C_CLK")
		)
		(pad "3" smd rect
			(at 7.74954 -10.6172)
			(size 0.3048 1.27)
			(layers "F.Cu" "F.Mask" "F.Paste")
			(net "BMC_I2C_ALERT#")
		)
		(pad "4" smd rect
			(at 7.25043 -10.6172)
			(size 0.3048 1.27)
			(layers "F.Cu" "F.Mask" "F.Paste")
			(net "GND")
		)
		(pad "5" smd rect
			(at 6.75005 -10.6172)
			(size 0.3048 1.27)
			(layers "F.Cu" "F.Mask" "F.Paste")
			(net "P1V2_FPGA_D")
		)
		(pad "6" smd rect
			(at 6.24967 -10.6172)
			(size 0.3048 1.27)
			(layers "F.Cu" "F.Mask" "F.Paste")
			(net "FPGA_ASDO")
		)
		(pad "7" smd rect
			(at 5.75056 -10.6172)
			(size 0.3048 1.27)
			(layers "F.Cu" "F.Mask" "F.Paste")
			(net "Net_342")
		)
		(pad "8" smd rect
			(at 5.25018 -10.6172)
			(size 0.3048 1.27)
			(layers "F.Cu" "F.Mask" "F.Paste")
			(net "FPGA_CSO#")
		)
		(pad "9" smd rect
			(at 4.7498 -10.6172)
			(size 0.3048 1.27)
			(layers "F.Cu" "F.Mask" "F.Paste")
			(net "C_NSTATUS#")
		)
		(pad "10" smd rect
			(at 4.24942 -10.6172)
			(size 0.3048 1.27)
			(layers "F.Cu" "F.Mask" "F.Paste")
			(net "TEMP_1_ALERT#")
		)
		(pad "11" smd rect
			(at 3.75031 -10.6172)
			(size 0.3048 1.27)
			(layers "F.Cu" "F.Mask" "F.Paste")
			(net "Net_333")
		)
		(pad "12" smd rect
			(at 3.24993 -10.6172)
			(size 0.3048 1.27)
			(layers "F.Cu" "F.Mask" "F.Paste")
			(net "FPGA_DCLK")
		)
		(pad "13" smd rect
			(at 2.74955 -10.6172)
			(size 0.3048 1.27)
			(layers "F.Cu" "F.Mask" "F.Paste")
			(net "FPGA_DATA0")
		)
		(pad "14" smd rect
			(at 2.25044 -10.6172)
			(size 0.3048 1.27)
			(layers "F.Cu" "F.Mask" "F.Paste")
			(net "C_NCONFIG#")
		)
		(pad "15" smd rect
			(at 1.75006 -10.6172)
			(size 0.3048 1.27)
			(layers "F.Cu" "F.Mask" "F.Paste")
			(net "JTAG_PLD_TDI")
		)
		(pad "16" smd rect
			(at 1.24968 -10.6172)
			(size 0.3048 1.27)
			(layers "F.Cu" "F.Mask" "F.Paste")
			(net "JTAG_PLD_TCK")
		)
		(pad "17" smd rect
			(at 0.75057 -10.6172)
			(size 0.3048 1.27)
			(layers "F.Cu" "F.Mask" "F.Paste")
			(net "P3V3_STBY")
		)
		(pad "18" smd rect
			(at 0.25019 -10.6172)
			(size 0.3048 1.27)
			(layers "F.Cu" "F.Mask" "F.Paste")
			(net "JTAG_PLD_TMS")
		)
		(pad "19" smd rect
			(at -0.25019 -10.6172)
			(size 0.3048 1.27)
			(layers "F.Cu" "F.Mask" "F.Paste")
			(net "GND")
		)
		(pad "20" smd rect
			(at -0.75057 -10.6172)
			(size 0.3048 1.27)
			(layers "F.Cu" "F.Mask" "F.Paste")
			(net "JTAG_PLD_TDO")
		)
		(pad "21" smd rect
			(at -1.24968 -10.6172)
			(size 0.3048 1.27)
			(layers "F.Cu" "F.Mask" "F.Paste")
			(net "C_NCE#")
		)
		(pad "22" smd rect
			(at -1.75006 -10.6172)
			(size 0.3048 1.27)
			(layers "F.Cu" "F.Mask" "F.Paste")
			(net "GND")
		)
		(pad "23" smd rect
			(at -2.25044 -10.6172)
			(size 0.3048 1.27)
			(layers "F.Cu" "F.Mask" "F.Paste")
			(net "Net_340")
		)
		(pad "24" smd rect
			(at -2.74955 -10.6172)
			(size 0.3048 1.27)
			(layers "F.Cu" "F.Mask" "F.Paste")
			(net "FPGA_CLK_DP")
		)
		(pad "25" smd rect
			(at -3.24993 -10.6172)
			(size 0.3048 1.27)
			(layers "F.Cu" "F.Mask" "F.Paste")
			(net "Net_341")
		)
		(pad "26" smd rect
			(at -3.75031 -10.6172)
			(size 0.3048 1.27)
			(layers "F.Cu" "F.Mask" "F.Paste")
			(net "P3V3_STBY")
		)
		(pad "27" smd rect
			(at -4.24942 -10.6172)
			(size 0.3048 1.27)
			(layers "F.Cu" "F.Mask" "F.Paste")
			(net "GND")
		)
		(pad "28" smd rect
			(at -4.7498 -10.6172)
			(size 0.3048 1.27)
			(layers "F.Cu" "F.Mask" "F.Paste")
			(net "REV_CPU_FPGA_R_IO0")
		)
		(pad "29" smd rect
			(at -5.25018 -10.6172)
			(size 0.3048 1.27)
			(layers "F.Cu" "F.Mask" "F.Paste")
			(net "P1V2_FPGA_D")
		)
		(pad "30" smd rect
			(at -5.75056 -10.6172)
			(size 0.3048 1.27)
			(layers "F.Cu" "F.Mask" "F.Paste")
			(net "REV_CPU_FPGA_R_IO1")
		)
		(pad "31" smd rect
			(at -6.24967 -10.6172)
			(size 0.3048 1.27)
			(layers "F.Cu" "F.Mask" "F.Paste")
			(net "SLOT_ID3")
		)
		(pad "32" smd rect
			(at -6.75005 -10.6172)
			(size 0.3048 1.27)
			(layers "F.Cu" "F.Mask" "F.Paste")
			(net "SLOT_ID2")
		)
		(pad "33" smd rect
			(at -7.25043 -10.6172)
			(size 0.3048 1.27)
			(layers "F.Cu" "F.Mask" "F.Paste")
			(net "SLOT_ID1")
		)
		(pad "34" smd rect
			(at -7.74954 -10.6172)
			(size 0.3048 1.27)
			(layers "F.Cu" "F.Mask" "F.Paste")
			(net "SLOT_ID0")
		)
		(pad "35" smd rect
			(at -8.24992 -10.6172)
			(size 0.3048 1.27)
			(layers "F.Cu" "F.Mask" "F.Paste")
			(net "P2V5_STBY")
		)
		(pad "36" smd rect
			(at -8.7503 -10.6172)
			(size 0.3048 1.27)
			(layers "F.Cu" "F.Mask" "F.Paste")
			(net "GND")
		)
		(pad "37" smd rect
			(at -10.6172 -8.7503)
			(size 1.27 0.3048)
			(layers "F.Cu" "F.Mask" "F.Paste")
			(net "P1V2_FPGA_A")
		)
		(pad "38" smd rect
			(at -10.6172 -8.24992)
			(size 1.27 0.3048)
			(layers "F.Cu" "F.Mask" "F.Paste")
			(net "Net_348")
		)
		(pad "39" smd rect
			(at -10.6172 -7.74954)
			(size 1.27 0.3048)
			(layers "F.Cu" "F.Mask" "F.Paste")
			(net "Net_347")
		)
		(pad "40" smd rect
			(at -10.6172 -7.25043)
			(size 1.27 0.3048)
			(layers "F.Cu" "F.Mask" "F.Paste")
			(net "P3V3_STBY")
		)
		(pad "41" smd rect
			(at -10.6172 -6.75005)
			(size 1.27 0.3048)
			(layers "F.Cu" "F.Mask" "F.Paste")
			(net "GND")
		)
		(pad "42" smd rect
			(at -10.6172 -6.24967)
			(size 1.27 0.3048)
			(layers "F.Cu" "F.Mask" "F.Paste")
			(net "Net_332")
		)
		(pad "43" smd rect
			(at -10.6172 -5.75056)
			(size 1.27 0.3048)
			(layers "F.Cu" "F.Mask" "F.Paste")
			(net "LPC_CPU_CLKOUT0")
		)
		(pad "44" smd rect
			(at -10.6172 -5.25018)
			(size 1.27 0.3048)
			(layers "F.Cu" "F.Mask" "F.Paste")
			(net "Net_331")
		)
		(pad "45" smd rect
			(at -10.6172 -4.7498)
			(size 1.27 0.3048)
			(layers "F.Cu" "F.Mask" "F.Paste")
			(net "P1V2_FPGA_D")
		)
		(pad "46" smd rect
			(at -10.6172 -4.24942)
			(size 1.27 0.3048)
			(layers "F.Cu" "F.Mask" "F.Paste")
			(net "LPC_CPU_CLKRUN#")
		)
		(pad "47" smd rect
			(at -10.6172 -3.75031)
			(size 1.27 0.3048)
			(layers "F.Cu" "F.Mask" "F.Paste")
			(net "P3V3_STBY")
		)
		(pad "48" smd rect
			(at -10.6172 -3.24993)
			(size 1.27 0.3048)
			(layers "F.Cu" "F.Mask" "F.Paste")
			(net "GND")
		)
		(pad "49" smd rect
			(at -10.6172 -2.74955)
			(size 1.27 0.3048)
			(layers "F.Cu" "F.Mask" "F.Paste")
			(net "LPC_CPU_FRAME#")
		)
		(pad "50" smd rect
			(at -10.6172 -2.25044)
			(size 1.27 0.3048)
			(layers "F.Cu" "F.Mask" "F.Paste")
			(net "LPC_AD_3")
		)
		(pad "51" smd rect
			(at -10.6172 -1.75006)
			(size 1.27 0.3048)
			(layers "F.Cu" "F.Mask" "F.Paste")
			(net "LPC_AD_2")
		)
		(pad "52" smd rect
			(at -10.6172 -1.24968)
			(size 1.27 0.3048)
			(layers "F.Cu" "F.Mask" "F.Paste")
			(net "LPC_AD_1")
		)
		(pad "53" smd rect
			(at -10.6172 -0.75057)
			(size 1.27 0.3048)
			(layers "F.Cu" "F.Mask" "F.Paste")
			(net "LPC_AD_0")
		)
		(pad "54" smd rect
			(at -10.6172 -0.25019)
			(size 1.27 0.3048)
			(layers "F.Cu" "F.Mask" "F.Paste")
			(net "SMB_PECI_LV_DATA")
		)
		(pad "55" smd rect
			(at -10.6172 0.25019)
			(size 1.27 0.3048)
			(layers "F.Cu" "F.Mask" "F.Paste")
			(net "SMB_PECI_LV_CLK")
		)
		(pad "56" smd rect
			(at -10.6172 0.75057)
			(size 1.27 0.3048)
			(layers "F.Cu" "F.Mask" "F.Paste")
			(net "P3V3_STBY")
		)
		(pad "57" smd rect
			(at -10.6172 1.24968)
			(size 1.27 0.3048)
			(layers "F.Cu" "F.Mask" "F.Paste")
			(net "GND")
		)
		(pad "58" smd rect
			(at -10.6172 1.75006)
			(size 1.27 0.3048)
			(layers "F.Cu" "F.Mask" "F.Paste")
			(net "IRQ_CPU_LV_IERR#")
		)
		(pad "59" smd rect
			(at -10.6172 2.25044)
			(size 1.27 0.3048)
			(layers "F.Cu" "F.Mask" "F.Paste")
			(net "IRQ_CPU_SERIAL")
		)
		(pad "60" smd rect
			(at -10.6172 2.74955)
			(size 1.27 0.3048)
			(layers "F.Cu" "F.Mask" "F.Paste")
			(net "CPU_ERR_N0")
		)
		(pad "61" smd rect
			(at -10.6172 3.24993)
			(size 1.27 0.3048)
			(layers "F.Cu" "F.Mask" "F.Paste")
			(net "P1V2_FPGA_D")
		)
		(pad "62" smd rect
			(at -10.6172 3.75031)
			(size 1.27 0.3048)
			(layers "F.Cu" "F.Mask" "F.Paste")
			(net "P3V3_STBY")
		)
		(pad "63" smd rect
			(at -10.6172 4.24942)
			(size 1.27 0.3048)
			(layers "F.Cu" "F.Mask" "F.Paste")
			(net "GND")
		)
		(pad "64" smd rect
			(at -10.6172 4.7498)
			(size 1.27 0.3048)
			(layers "F.Cu" "F.Mask" "F.Paste")
			(net "CPU_ERR_N1")
		)
		(pad "65" smd rect
			(at -10.6172 5.25018)
			(size 1.27 0.3048)
			(layers "F.Cu" "F.Mask" "F.Paste")
			(net "CPU_ERR_N2")
		)
		(pad "66" smd rect
			(at -10.6172 5.75056)
			(size 1.27 0.3048)
			(layers "F.Cu" "F.Mask" "F.Paste")
			(net "IRQ_LV_MCERR#")
		)
		(pad "67" smd rect
			(at -10.6172 6.24967)
			(size 1.27 0.3048)
			(layers "F.Cu" "F.Mask" "F.Paste")
			(net "MEMORY_FPGA_HOT#")
		)
		(pad "68" smd rect
			(at -10.6172 6.75005)
			(size 1.27 0.3048)
			(layers "F.Cu" "F.Mask" "F.Paste")
			(net "IRQ_NMI")
		)
		(pad "69" smd rect
			(at -10.6172 7.25043)
			(size 1.27 0.3048)
			(layers "F.Cu" "F.Mask" "F.Paste")
			(net "PROCESSOR_HOT_LVC#")
		)
		(pad "70" smd rect
			(at -10.6172 7.74954)
			(size 1.27 0.3048)
			(layers "F.Cu" "F.Mask" "F.Paste")
			(net "PMU_SLP_R_S45#")
		)
		(pad "71" smd rect
			(at -10.6172 8.24992)
			(size 1.27 0.3048)
			(layers "F.Cu" "F.Mask" "F.Paste")
			(net "PMU_PLD_R_PLTRST#")
		)
		(pad "72" smd rect
			(at -10.6172 8.7503)
			(size 1.27 0.3048)
			(layers "F.Cu" "F.Mask" "F.Paste")
			(net "PVCCP_PVNN_VRHOT#")
		)
		(pad "73" smd rect
			(at -8.7503 10.6172)
			(size 0.3048 1.27)
			(layers "F.Cu" "F.Mask" "F.Paste")
			(net "CPU_THERMTRIP_LVC#")
		)
		(pad "74" smd rect
			(at -8.24992 10.6172)
			(size 0.3048 1.27)
			(layers "F.Cu" "F.Mask" "F.Paste")
			(net "BIOS_POST_COMPLETE_R")
		)
		(pad "75" smd rect
			(at -7.74954 10.6172)
			(size 0.3048 1.27)
			(layers "F.Cu" "F.Mask" "F.Paste")
			(net "POWER_GOOD_R")
		)
		(pad "76" smd rect
			(at -7.25043 10.6172)
			(size 0.3048 1.27)
			(layers "F.Cu" "F.Mask" "F.Paste")
			(net "POWER_CONTROL")
		)
		(pad "77" smd rect
			(at -6.75005 10.6172)
			(size 0.3048 1.27)
			(layers "F.Cu" "F.Mask" "F.Paste")
			(net "HOST_RSTBTN#")
		)
		(pad "78" smd rect
			(at -6.24967 10.6172)
			(size 0.3048 1.27)
			(layers "F.Cu" "F.Mask" "F.Paste")
			(net "P1V2_FPGA_D")
		)
		(pad "79" smd rect
			(at -5.75056 10.6172)
			(size 0.3048 1.27)
			(layers "F.Cu" "F.Mask" "F.Paste")
			(net "GND")
		)
		(pad "80" smd rect
			(at -5.25018 10.6172)
			(size 0.3048 1.27)
			(layers "F.Cu" "F.Mask" "F.Paste")
			(net "Net_343")
		)
		(pad "81" smd rect
			(at -4.7498 10.6172)
			(size 0.3048 1.27)
			(layers "F.Cu" "F.Mask" "F.Paste")
			(net "P3V3_STBY")
		)
		(pad "82" smd rect
			(at -4.24942 10.6172)
			(size 0.3048 1.27)
			(layers "F.Cu" "F.Mask" "F.Paste")
			(net "GND")
		)
		(pad "83" smd rect
			(at -3.75031 10.6172)
			(size 0.3048 1.27)
			(layers "F.Cu" "F.Mask" "F.Paste")
			(net "TP_FPGA_P84")
		)
		(pad "84" smd rect
			(at -3.24993 10.6172)
			(size 0.3048 1.27)
			(layers "F.Cu" "F.Mask" "F.Paste")
			(net "TP_FPGA_P85")
		)
		(pad "85" smd rect
			(at -2.74955 10.6172)
			(size 0.3048 1.27)
			(layers "F.Cu" "F.Mask" "F.Paste")
			(net "Net_346")
		)
		(pad "86" smd rect
			(at -2.25044 10.6172)
			(size 0.3048 1.27)
			(layers "F.Cu" "F.Mask" "F.Paste")
			(net "Net_339")
		)
		(pad "87" smd rect
			(at -1.75006 10.6172)
			(size 0.3048 1.27)
			(layers "F.Cu" "F.Mask" "F.Paste")
			(net "GND")
		)
		(pad "88" smd rect
			(at -1.24968 10.6172)
			(size 0.3048 1.27)
			(layers "F.Cu" "F.Mask" "F.Paste")
			(net "Net_97")
		)
		(pad "89" smd rect
			(at -0.75057 10.6172)
			(size 0.3048 1.27)
			(layers "F.Cu" "F.Mask" "F.Paste")
			(net "Net_98")
		)
		(pad "90" smd rect
			(at -0.25019 10.6172)
			(size 0.3048 1.27)
			(layers "F.Cu" "F.Mask" "F.Paste")
			(net "GND")
		)
		(pad "91" smd rect
			(at 0.25019 10.6172)
			(size 0.3048 1.27)
			(layers "F.Cu" "F.Mask" "F.Paste")
			(net "Net_336")
		)
		(pad "92" smd rect
			(at 0.75057 10.6172)
			(size 0.3048 1.27)
			(layers "F.Cu" "F.Mask" "F.Paste")
			(net "C_CONF_DONE")
		)
		(pad "93" smd rect
			(at 1.24968 10.6172)
			(size 0.3048 1.27)
			(layers "F.Cu" "F.Mask" "F.Paste")
			(net "P3V3_STBY")
		)
		(pad "94" smd rect
			(at 1.75006 10.6172)
			(size 0.3048 1.27)
			(layers "F.Cu" "F.Mask" "F.Paste")
			(net "MSEL0")
		)
		(pad "95" smd rect
			(at 2.25044 10.6172)
			(size 0.3048 1.27)
			(layers "F.Cu" "F.Mask" "F.Paste")
			(net "GND")
		)
		(pad "96" smd rect
			(at 2.74955 10.6172)
			(size 0.3048 1.27)
			(layers "F.Cu" "F.Mask" "F.Paste")
			(net "MSEL1")
		)
		(pad "97" smd rect
			(at 3.24993 10.6172)
			(size 0.3048 1.27)
			(layers "F.Cu" "F.Mask" "F.Paste")
			(net "MSEL2")
		)
		(pad "98" smd rect
			(at 3.75031 10.6172)
			(size 0.3048 1.27)
			(layers "F.Cu" "F.Mask" "F.Paste")
			(net "Net_338")
		)
		(pad "99" smd rect
			(at 4.24942 10.6172)
			(size 0.3048 1.27)
			(layers "F.Cu" "F.Mask" "F.Paste")
			(net "Net_337")
		)
		(pad "100" smd rect
			(at 4.7498 10.6172)
			(size 0.3048 1.27)
			(layers "F.Cu" "F.Mask" "F.Paste")
			(net "TP_FPGA_P100")
		)
		(pad "101" smd rect
			(at 5.25018 10.6172)
			(size 0.3048 1.27)
			(layers "F.Cu" "F.Mask" "F.Paste")
			(net "C_CEO#")
		)
		(pad "102" smd rect
			(at 5.75056 10.6172)
			(size 0.3048 1.27)
			(layers "F.Cu" "F.Mask" "F.Paste")
			(net "P1V2_FPGA_D")
		)
		(pad "103" smd rect
			(at 6.24967 10.6172)
			(size 0.3048 1.27)
			(layers "F.Cu" "F.Mask" "F.Paste")
			(net "Net_335")
		)
		(pad "104" smd rect
			(at 6.75005 10.6172)
			(size 0.3048 1.27)
			(layers "F.Cu" "F.Mask" "F.Paste")
			(net "Net_323")
		)
		(pad "105" smd rect
			(at 7.25043 10.6172)
			(size 0.3048 1.27)
			(layers "F.Cu" "F.Mask" "F.Paste")
			(net "Net_344")
		)
		(pad "106" smd rect
			(at 7.74954 10.6172)
			(size 0.3048 1.27)
			(layers "F.Cu" "F.Mask" "F.Paste")
			(net "Net_324")
		)
		(pad "107" smd rect
			(at 8.24992 10.6172)
			(size 0.3048 1.27)
			(layers "F.Cu" "F.Mask" "F.Paste")
			(net "P2V5_STBY")
		)
		(pad "108" smd rect
			(at 8.7503 10.6172)
			(size 0.3048 1.27)
			(layers "F.Cu" "F.Mask" "F.Paste")
			(net "GND")
		)
		(pad "109" smd rect
			(at 10.6172 8.7503)
			(size 1.27 0.3048)
			(layers "F.Cu" "F.Mask" "F.Paste")
			(net "P1V2_FPGA_A")
		)
		(pad "110" smd rect
			(at 10.6172 8.24992)
			(size 1.27 0.3048)
			(layers "F.Cu" "F.Mask" "F.Paste")
			(net "TP_FPGA_P110")
		)
		(pad "111" smd rect
			(at 10.6172 7.74954)
			(size 1.27 0.3048)
			(layers "F.Cu" "F.Mask" "F.Paste")
			(net "TP_FPGA_P111")
		)
		(pad "112" smd rect
			(at 10.6172 7.25043)
			(size 1.27 0.3048)
			(layers "F.Cu" "F.Mask" "F.Paste")
			(net "TP_FPGA_P112")
		)
		(pad "113" smd rect
			(at 10.6172 6.75005)
			(size 1.27 0.3048)
			(layers "F.Cu" "F.Mask" "F.Paste")
			(net "TP_FPGA_P113")
		)
		(pad "114" smd rect
			(at 10.6172 6.24967)
			(size 1.27 0.3048)
			(layers "F.Cu" "F.Mask" "F.Paste")
			(net "Net_326")
		)
		(pad "115" smd rect
			(at 10.6172 5.75056)
			(size 1.27 0.3048)
			(layers "F.Cu" "F.Mask" "F.Paste")
			(net "Net_325")
		)
		(pad "116" smd rect
			(at 10.6172 5.25018)
			(size 1.27 0.3048)
			(layers "F.Cu" "F.Mask" "F.Paste")
			(net "P1V2_FPGA_D")
		)
		(pad "117" smd rect
			(at 10.6172 4.7498)
			(size 1.27 0.3048)
			(layers "F.Cu" "F.Mask" "F.Paste")
			(net "P3V3_STBY")
		)
		(pad "118" smd rect
			(at 10.6172 4.24942)
			(size 1.27 0.3048)
			(layers "F.Cu" "F.Mask" "F.Paste")
			(net "GND")
		)
		(pad "119" smd rect
			(at 10.6172 3.75031)
			(size 1.27 0.3048)
			(layers "F.Cu" "F.Mask" "F.Paste")
			(net "Net_345")
		)
		(pad "120" smd rect
			(at 10.6172 3.24993)
			(size 1.27 0.3048)
			(layers "F.Cu" "F.Mask" "F.Paste")
			(net "FPGA_SMB_HOST_CLK")
		)
		(pad "121" smd rect
			(at 10.6172 2.74955)
			(size 1.27 0.3048)
			(layers "F.Cu" "F.Mask" "F.Paste")
			(net "FPGA_SMB_HOST_DATA")
		)
	)
)
